FILE_TYPE=LIBRARY_PARTS;
primitive 'SN74AVC4T774PWR';
  pin
    'DIR1':
      PIN_NUMBER='(1)';
      INPUT_LOAD='(-0.01,0.01)';
    'DIR2':
      PIN_NUMBER='(2)';
      INPUT_LOAD='(-0.01,0.01)';
    'A1':
      PIN_NUMBER='(3)';
      BIDIRECTIONAL='TRUE';
      INPUT_LOAD='(-0.01,0.01)';
      OUTPUT_LOAD='(1.0,-1.0)';
    'A2':
      PIN_NUMBER='(4)';
      BIDIRECTIONAL='TRUE';
      INPUT_LOAD='(-0.01,0.01)';
      OUTPUT_LOAD='(1.0,-1.0)';
    'A3':
      PIN_NUMBER='(5)';
      BIDIRECTIONAL='TRUE';
      INPUT_LOAD='(-0.01,0.01)';
      OUTPUT_LOAD='(1.0,-1.0)';
    'A4':
      PIN_NUMBER='(6)';
      BIDIRECTIONAL='TRUE';
      INPUT_LOAD='(-0.01,0.01)';
      OUTPUT_LOAD='(1.0,-1.0)';
    'DIR3':
      PIN_NUMBER='(7)';
      INPUT_LOAD='(-0.01,0.01)';
    'DIR4':
      PIN_NUMBER='(8)';
      INPUT_LOAD='(-0.01,0.01)';
    'OE':
      PIN_NUMBER='(9)';
      INPUT_LOAD='(-0.01,0.01)';
    'GND':
      PIN_NUMBER='(10)';
      PINUSE='POWER';
      NO_LOAD_CHECK='Both';
      NO_IO_CHECK='Both';
      NO_ASSERT_CHECK='TRUE';
      NO_DIR_CHECK='TRUE';
      ALLOW_CONNECT='TRUE';
    'B4':
      PIN_NUMBER='(11)';
      BIDIRECTIONAL='TRUE';
      INPUT_LOAD='(-0.01,0.01)';
      OUTPUT_LOAD='(1.0,-1.0)';
    'B3':
      PIN_NUMBER='(12)';
      BIDIRECTIONAL='TRUE';
      INPUT_LOAD='(-0.01,0.01)';
      OUTPUT_LOAD='(1.0,-1.0)';
    'B2':
      PIN_NUMBER='(13)';
      BIDIRECTIONAL='TRUE';
      INPUT_LOAD='(-0.01,0.01)';
      OUTPUT_LOAD='(1.0,-1.0)';
    'B1':
      PIN_NUMBER='(14)';
      BIDIRECTIONAL='TRUE';
      INPUT_LOAD='(-0.01,0.01)';
      OUTPUT_LOAD='(1.0,-1.0)';
    'VCCB':
      PIN_NUMBER='(15)';
      PINUSE='POWER';
      NO_LOAD_CHECK='Both';
      NO_IO_CHECK='Both';
      NO_ASSERT_CHECK='TRUE';
      NO_DIR_CHECK='TRUE';
      ALLOW_CONNECT='TRUE';
    'VCCA':
      PIN_NUMBER='(16)';
      PINUSE='POWER';
      NO_LOAD_CHECK='Both';
      NO_IO_CHECK='Both';
      NO_ASSERT_CHECK='TRUE';
      NO_DIR_CHECK='TRUE';
      ALLOW_CONNECT='TRUE';
  end_pin;
  body
    PART_NAME='SN74AVC4T774PWR';
    BODY_NAME='SN74AVC4T774PWR';
    PHYS_DES_PREFIX='U';
    CLASS='IC';
  end_body;
end_primitive;

END.
